(kicad_pcb
	(version 20221018)
	(generator pcbnew)
	(general
    (thickness 1.7403)
  )
	(paper "A4")
	(title_block
    (title "Data Center RDIMM DDR4 Tester")
    (date "2024-09-30")
    (rev "1.2.4")
		(comment 9 "footprints 189-196 of 690")
	)
	(layers
    (0 "F.Cu" signal)
    (1 "In1.Cu" power)
    (2 "In2.Cu" signal)
    (3 "In3.Cu" power)
    (4 "In4.Cu" power)
    (5 "In5.Cu" signal)
    (6 "In6.Cu" power)
    (7 "In7.Cu" signal)
    (8 "In8.Cu" power)
    (9 "In9.Cu" signal)
    (10 "In10.Cu" power)
    (31 "B.Cu" signal)
    (32 "B.Adhes" user "B.Adhesive")
    (33 "F.Adhes" user "F.Adhesive")
    (34 "B.Paste" user)
    (35 "F.Paste" user)
    (36 "B.SilkS" user "B.Silkscreen")
    (37 "F.SilkS" user "F.Silkscreen")
    (38 "B.Mask" user)
    (39 "F.Mask" user)
    (40 "Dwgs.User" user "User.Drawings")
    (41 "Cmts.User" user "User.Comments")
    (42 "Eco1.User" user "User.Eco1")
    (43 "Eco2.User" user "User.Eco2")
    (44 "Edge.Cuts" user)
    (45 "Margin" user)
    (46 "B.CrtYd" user "B.Courtyard")
    (47 "F.CrtYd" user "F.Courtyard")
    (48 "B.Fab" user)
    (49 "F.Fab" user)
  )
	(footprint "data-center-rdimm-ddr4-tester-footprints:C_0402_1005Metric" (layer "F.Cu")
    (at 120.136328 95.81)
    (descr "Capacitor SMD 0402")
    (tags "capacitor SMD 0402")
    (property "Author" "Antmicro")
    (property "Dielectric" "X5R")
    (property "License" "Apache-2.0")
    (property "MPN" "GRM155R61H104KE14D")
    (property "Manufacturer" "Murata")
    (property "Sheetfile" "supply.kicad_sch")
    (property "Sheetname" "Supply")
    (property "Val" "100n")
    (property "Voltage" "50V")
    (property "ki_description" " ")
    (attr smd)
    (fp_text reference "C35" (at 0.353672 1.3) (layer "F.SilkS")
        (effects (font (size 0.7 0.7) (thickness 0.15)) (justify left bottom))
    )
    (fp_text value "C_100n_0402" (at 0 1.4) (layer "F.Fab") hide
        (effects (font (size 0.7 0.7) (thickness 0.15)) (justify left bottom))
    )
    (fp_text user "${REFERENCE}" (at -0.932 3.168) (layer "F.Fab") hide
        (effects (font (size 0.7 0.7) (thickness 0.15)) (justify left bottom))
    )
    (fp_text user "Author: Antmicro" (at -0.932 4.17) (layer "F.Fab") hide
        (effects (font (size 0.7 0.7) (thickness 0.15)) (justify left bottom))
    )
    (fp_text user "License: Apache-2.0" (at -0.932 5.17) (layer "F.Fab") hide
        (effects (font (size 0.7 0.7) (thickness 0.15)) (justify left bottom))
    )
    (fp_rect (start -0.94 -0.47) (end 0.94 0.47)
      (stroke (width 0.05) (type solid)) (fill none) (layer "F.CrtYd"))
    (fp_rect (start -0.499 -0.249) (end 0.499 0.249)
      (stroke (width 0.15) (type solid)) (fill none) (layer "F.Fab"))
    (pad "1" smd roundrect (at -0.484 0) (size 0.59 0.64) (layers "F.Cu" "F.Paste" "F.Mask") (roundrect_rratio 0.25)
      (net 105 "Net-(C35-Pad1)") (pintype "passive"))
    (pad "2" smd roundrect (at 0.484 0) (size 0.59 0.64) (layers "F.Cu" "F.Paste" "F.Mask") (roundrect_rratio 0.25)
      (net 1 "Net-(U2-SW)") (pintype "passive"))
  )
	(footprint "data-center-rdimm-ddr4-tester-footprints:C_0402_1005Metric" (layer "F.Cu")
    (at 119.411328 114.497157 180)
    (descr "Capacitor SMD 0402")
    (tags "capacitor SMD 0402")
    (property "Author" "Antmicro")
    (property "Dielectric" "")
    (property "License" "Apache-2.0")
    (property "MPN" "CGA2B3X7S2A472K050BB")
    (property "Manufacturer" "TDK")
    (property "Sheetfile" "supply.kicad_sch")
    (property "Sheetname" "Supply")
    (property "Val" "4n7")
    (property "Voltage" "")
    (property "ki_description" " ")
    (attr smd)
    (fp_text reference "C172" (at 4.911328 -3.222843 180) (layer "F.SilkS")
        (effects (font (size 0.7 0.7) (thickness 0.15)) (justify left bottom))
    )
    (fp_text value "C_4n7_0402" (at 0 1.4 180) (layer "F.Fab") hide
        (effects (font (size 0.7 0.7) (thickness 0.15)) (justify left bottom))
    )
    (fp_text user "License: Apache-2.0" (at -0.932 5.17 180) (layer "F.Fab") hide
        (effects (font (size 0.7 0.7) (thickness 0.15)) (justify left bottom))
    )
    (fp_text user "${REFERENCE}" (at -0.932 3.168 180) (layer "F.Fab") hide
        (effects (font (size 0.7 0.7) (thickness 0.15)) (justify left bottom))
    )
    (fp_text user "Author: Antmicro" (at -0.932 4.17 180) (layer "F.Fab") hide
        (effects (font (size 0.7 0.7) (thickness 0.15)) (justify left bottom))
    )
    (fp_rect (start -0.94 -0.47) (end 0.94 0.47)
      (stroke (width 0.05) (type solid)) (fill none) (layer "F.CrtYd"))
    (fp_rect (start -0.499 -0.249) (end 0.499 0.249)
      (stroke (width 0.15) (type solid)) (fill none) (layer "F.Fab"))
    (pad "1" smd roundrect (at -0.484 0 180) (size 0.59 0.64) (layers "F.Cu" "F.Paste" "F.Mask") (roundrect_rratio 0.25)
      (net 107 "Net-(C172-Pad1)") (pintype "passive"))
    (pad "2" smd roundrect (at 0.484 0 180) (size 0.59 0.64) (layers "F.Cu" "F.Paste" "F.Mask") (roundrect_rratio 0.25)
      (net 9 "GND") (pintype "passive"))
  )
	(footprint "data-center-rdimm-ddr4-tester-footprints:C_0402_1005Metric" (layer "F.Cu")
    (at 123.917728 71.655008 90)
    (descr "Capacitor SMD 0402")
    (tags "capacitor SMD 0402")
    (property "Author" "Antmicro")
    (property "Dielectric" "X5R")
    (property "License" "Apache-2.0")
    (property "MPN" "GRM155R61H104KE14D")
    (property "Manufacturer" "Murata")
    (property "Sheetfile" "fpga-banks-16-34.kicad_sch")
    (property "Sheetname" "FPGA banks 16-34")
    (property "Val" "100n")
    (property "Voltage" "50V")
    (property "ki_description" " ")
    (attr smd)
    (fp_text reference "C206" (at -1.364992 1.322272 90) (layer "F.SilkS")
        (effects (font (size 0.7 0.7) (thickness 0.15)) (justify left bottom))
    )
    (fp_text value "C_100n_0402" (at 0 1.4 90) (layer "F.Fab") hide
        (effects (font (size 0.7 0.7) (thickness 0.15)) (justify left bottom))
    )
    (fp_text user "${REFERENCE}" (at -0.932 3.168 90) (layer "F.Fab") hide
        (effects (font (size 0.7 0.7) (thickness 0.15)) (justify left bottom))
    )
    (fp_text user "Author: Antmicro" (at -0.932 4.17 90) (layer "F.Fab") hide
        (effects (font (size 0.7 0.7) (thickness 0.15)) (justify left bottom))
    )
    (fp_text user "License: Apache-2.0" (at -0.932 5.17 90) (layer "F.Fab") hide
        (effects (font (size 0.7 0.7) (thickness 0.15)) (justify left bottom))
    )
    (fp_rect (start -0.94 -0.47) (end 0.94 0.47)
      (stroke (width 0.05) (type solid)) (fill none) (layer "F.CrtYd"))
    (fp_rect (start -0.499 -0.249) (end 0.499 0.249)
      (stroke (width 0.15) (type solid)) (fill none) (layer "F.Fab"))
    (pad "1" smd roundrect (at -0.484 0 90) (size 0.59 0.64) (layers "F.Cu" "F.Paste" "F.Mask") (roundrect_rratio 0.25)
      (net 143 "3V3_SYS") (pintype "passive"))
    (pad "2" smd roundrect (at 0.484 0 90) (size 0.59 0.64) (layers "F.Cu" "F.Paste" "F.Mask") (roundrect_rratio 0.25)
      (net 9 "GND") (pintype "passive"))
  )
	(footprint "data-center-rdimm-ddr4-tester-footprints:C_0402_1005Metric" (layer "F.Cu")
    (at 123.917728 68.225008 -90)
    (descr "Capacitor SMD 0402")
    (tags "capacitor SMD 0402")
    (property "Author" "Antmicro")
    (property "Dielectric" "X5R")
    (property "License" "Apache-2.0")
    (property "MPN" "GRM155R61H104KE14D")
    (property "Manufacturer" "Murata")
    (property "Sheetfile" "fpga-banks-16-34.kicad_sch")
    (property "Sheetname" "FPGA banks 16-34")
    (property "Val" "100n")
    (property "Voltage" "50V")
    (property "ki_description" " ")
    (attr smd)
    (fp_text reference "C207" (at 1.494992 -1.322272 -90) (layer "F.SilkS")
        (effects (font (size 0.7 0.7) (thickness 0.15)) (justify left bottom))
    )
    (fp_text value "C_100n_0402" (at 0 1.4 -90) (layer "F.Fab") hide
        (effects (font (size 0.7 0.7) (thickness 0.15)) (justify left bottom))
    )
    (fp_text user "Author: Antmicro" (at -0.932 4.17 -90) (layer "F.Fab") hide
        (effects (font (size 0.7 0.7) (thickness 0.15)) (justify left bottom))
    )
    (fp_text user "${REFERENCE}" (at -0.932 3.168 -90) (layer "F.Fab") hide
        (effects (font (size 0.7 0.7) (thickness 0.15)) (justify left bottom))
    )
    (fp_text user "License: Apache-2.0" (at -0.932 5.17 -90) (layer "F.Fab") hide
        (effects (font (size 0.7 0.7) (thickness 0.15)) (justify left bottom))
    )
    (fp_rect (start -0.94 -0.47) (end 0.94 0.47)
      (stroke (width 0.05) (type solid)) (fill none) (layer "F.CrtYd"))
    (fp_rect (start -0.499 -0.249) (end 0.499 0.249)
      (stroke (width 0.15) (type solid)) (fill none) (layer "F.Fab"))
    (pad "1" smd roundrect (at -0.484 0 270) (size 0.59 0.64) (layers "F.Cu" "F.Paste" "F.Mask") (roundrect_rratio 0.25)
      (net 185 "VDDSPD") (pintype "passive"))
    (pad "2" smd roundrect (at 0.484 0 270) (size 0.59 0.64) (layers "F.Cu" "F.Paste" "F.Mask") (roundrect_rratio 0.25)
      (net 9 "GND") (pintype "passive"))
  )
	(footprint "data-center-rdimm-ddr4-tester-footprints:TSSOP-8_3x3mm_P0.65mm" (layer "F.Cu")
    (at 121.55 69.875 -90)
    (property "Author" "Antmicro")
    (property "License" "Apache-2.0")
    (property "MPN" "PCA9517ADMR2G")
    (property "Manufacturer" "ON Semiconductor")
    (property "Sheetfile" "fpga-banks-16-34.kicad_sch")
    (property "Sheetname" "FPGA banks 16-34")
    (property "ki_description" "Translation - Voltage Levels LEVEL TRANSLATING I2")
    (property "ki_keywords" "Translation - Voltage Levels LEVEL TRANSLATING I2")
    (attr smd)
    (fp_text reference "U8" (at -1.105 1.76 90) (layer "F.SilkS")
        (effects (font (size 0.7 0.7) (thickness 0.15)) (justify right bottom))
    )
    (fp_text value "PCA9517A_TSSOP" (at 0 2.8 90) (layer "F.Fab") hide
        (effects (font (size 0.7 0.7) (thickness 0.15)) (justify right bottom))
    )
    (fp_text user "${REFERENCE}" (at -1.789 6.58 90) (layer "F.Fab") hide
        (effects (font (size 0.7 0.7) (thickness 0.15)) (justify right bottom))
    )
    (fp_text user "Author: Antmicro" (at -1.789 7.78 90) (layer "F.Fab") hide
        (effects (font (size 0.7 0.7) (thickness 0.15)) (justify right bottom))
    )
    (fp_text user "License: Apache-2.0" (at -1.789 8.98 90) (layer "F.Fab") hide
        (effects (font (size 0.7 0.7) (thickness 0.15)) (justify right bottom))
    )
    (fp_line (start -1.55 1.561) (end 1.552 1.561)
      (stroke (width 0.15) (type solid)) (layer "F.SilkS"))
    (fp_line (start -1.525 -1.537) (end 1.552 -1.539)
      (stroke (width 0.15) (type solid)) (layer "F.SilkS"))
    (fp_circle (center -1.87 -1.4) (end -1.82 -1.4)
      (stroke (width 0.15) (type solid)) (fill solid) (layer "F.SilkS"))
    (fp_rect (start -3.15 -1.789) (end 3.15 1.811)
      (stroke (width 0.05) (type solid)) (fill none) (layer "F.CrtYd"))
    (fp_line (start -1.55 -0.937) (end -1.55 1.561)
      (stroke (width 0.15) (type solid)) (layer "F.Fab"))
    (fp_line (start -1.55 -0.937) (end -0.949 -1.539)
      (stroke (width 0.15) (type solid)) (layer "F.Fab"))
    (fp_line (start -1.55 1.561) (end 1.552 1.561)
      (stroke (width 0.15) (type solid)) (layer "F.Fab"))
    (fp_line (start -0.949 -1.539) (end 1.552 -1.539)
      (stroke (width 0.15) (type solid)) (layer "F.Fab"))
    (fp_line (start 1.552 -1.539) (end 1.552 1.561)
      (stroke (width 0.15) (type solid)) (layer "F.Fab"))
    (pad "1" smd roundrect (at -2.148 -0.962 270) (size 1.47 0.4) (layers "F.Cu" "F.Paste" "F.Mask") (roundrect_rratio 0.25)
      (net 185 "VDDSPD") (pinfunction "VREF_{1}") (pintype "power_in"))
    (pad "2" smd roundrect (at -2.148 -0.313 270) (size 1.47 0.4) (layers "F.Cu" "F.Paste" "F.Mask") (roundrect_rratio 0.25)
      (net 351 "SCL_2V5") (pinfunction "SCL_{1}") (pintype "bidirectional"))
    (pad "3" smd roundrect (at -2.148 0.338 270) (size 1.47 0.4) (layers "F.Cu" "F.Paste" "F.Mask") (roundrect_rratio 0.25)
      (net 350 "SDA_2V5") (pinfunction "SDA_{1}") (pintype "bidirectional"))
    (pad "4" smd roundrect (at -2.148 0.987 270) (size 1.47 0.4) (layers "F.Cu" "F.Paste" "F.Mask") (roundrect_rratio 0.25)
      (net 9 "GND") (pinfunction "GND") (pintype "power_in"))
    (pad "5" smd roundrect (at 2.151 0.987 270) (size 1.47 0.4) (layers "F.Cu" "F.Paste" "F.Mask") (roundrect_rratio 0.25)
      (net 666 "Net-(U8-EN)") (pinfunction "EN") (pintype "input"))
    (pad "6" smd roundrect (at 2.151 0.338 270) (size 1.47 0.4) (layers "F.Cu" "F.Paste" "F.Mask") (roundrect_rratio 0.25)
      (net 357 "SDA_3V3") (pinfunction "SDA_{2}") (pintype "bidirectional"))
    (pad "7" smd roundrect (at 2.151 -0.313 270) (size 1.47 0.4) (layers "F.Cu" "F.Paste" "F.Mask") (roundrect_rratio 0.25)
      (net 358 "SCL_3V3") (pinfunction "SCL_{2}") (pintype "bidirectional"))
    (pad "8" smd roundrect (at 2.151 -0.962 270) (size 1.47 0.4) (layers "F.Cu" "F.Paste" "F.Mask") (roundrect_rratio 0.25)
      (net 143 "3V3_SYS") (pinfunction "VREF_{2}") (pintype "power_in"))
  )
	(footprint "data-center-rdimm-ddr4-tester-footprints:R_0402_1005Metric" (layer "F.Cu")
    (at 120.586328 66.185008)
    (descr "Resistor SMD 0402")
    (tags "resistor SMD 0402")
    (property "Author" "Antmicro")
    (property "License" "Apache-2.0")
    (property "MPN" "CR0402-FX-4701GLF")
    (property "Manufacturer" "Bourns")
    (property "Sheetfile" "fpga-banks-16-34.kicad_sch")
    (property "Sheetname" "FPGA banks 16-34")
    (property "Tolerance" "1%")
    (property "Val" "4k7")
    (property "ki_description" "4k7 resistor in 0402 package with 1% tolerance")
    (attr smd)
    (fp_text reference "R173" (at -3.606328 0.324992) (layer "F.SilkS")
        (effects (font (size 0.7 0.7) (thickness 0.15)) (justify left bottom))
    )
    (fp_text value "R_4k7_0402" (at 0 1.4) (layer "F.Fab") hide
        (effects (font (size 0.7 0.7) (thickness 0.15)) (justify left bottom))
    )
    (fp_text user "${REFERENCE}" (at -0.95 3.168) (layer "F.Fab") hide
        (effects (font (size 0.7 0.7) (thickness 0.15)) (justify left bottom))
    )
    (fp_text user "License: Apache-2.0" (at -0.95 5.169) (layer "F.Fab") hide
        (effects (font (size 0.7 0.7) (thickness 0.15)) (justify left bottom))
    )
    (fp_text user "Author: Antmicro" (at -0.95 4.169) (layer "F.Fab") hide
        (effects (font (size 0.7 0.7) (thickness 0.15)) (justify left bottom))
    )
    (fp_rect (start -0.93 -0.47) (end 0.93 0.47)
      (stroke (width 0.05) (type solid)) (fill none) (layer "F.CrtYd"))
    (fp_rect (start -0.5 -0.25) (end 0.5 0.25)
      (stroke (width 0.15) (type solid)) (fill none) (layer "F.Fab"))
    (pad "1" smd roundrect (at -0.485 0) (size 0.59 0.64) (layers "F.Cu" "F.Paste" "F.Mask") (roundrect_rratio 0.25)
      (net 185 "VDDSPD") (pintype "passive"))
    (pad "2" smd roundrect (at 0.485 0) (size 0.59 0.64) (layers "F.Cu" "F.Paste" "F.Mask") (roundrect_rratio 0.25)
      (net 350 "SDA_2V5") (pintype "passive"))
  )
	(footprint "data-center-rdimm-ddr4-tester-footprints:L_1716_4441Metric" (layer "F.Cu")
    (at 148.299328 117.477008 -90)
    (property "Author" "Antmicro")
    (property "License" "Apache-2.0")
    (property "MPN" "SRP0420-1R5K")
    (property "Manufacturer" "Bourns")
    (property "MaxCur" "6A")
    (property "Sheetfile" "supply.kicad_sch")
    (property "Sheetname" "Supply")
    (property "Size" "4.40x4.10")
    (property "Val" "1u5/6A")
    (attr smd)
    (fp_text reference "L4" (at 2.942992 2.249328 -90) (layer "F.SilkS")
        (effects (font (size 0.7 0.7) (thickness 0.15)) (justify left bottom))
    )
    (fp_text value "L_1u5_6A_1716" (at 0 3.3 -90) (layer "F.Fab") hide
        (effects (font (size 0.7 0.7) (thickness 0.15)) (justify left bottom))
    )
    (fp_text user "License: Apache-2.0" (at -17.726 19.484 -90) (layer "F.Fab") hide
        (effects (font (size 0.7 0.7) (thickness 0.15)) (justify left bottom))
    )
    (fp_text user "Author: Antmicro" (at -17.726 18.283 -90) (layer "F.Fab") hide
        (effects (font (size 0.7 0.7) (thickness 0.15)) (justify left bottom))
    )
    (fp_text user "${REFERENCE}" (at -17.726 17.083 -90) (layer "F.Fab") hide
        (effects (font (size 0.7 0.7) (thickness 0.15)) (justify left bottom))
    )
    (fp_line (start -2.202 -2.0555) (end 2.248 -2.0555)
      (stroke (width 0.15) (type solid)) (layer "F.SilkS"))
    (fp_line (start -2.202 -1.5265) (end -2.202 -2.0555)
      (stroke (width 0.15) (type solid)) (layer "F.SilkS"))
    (fp_line (start -2.202 2.0535) (end -2.202 1.5245)
      (stroke (width 0.15) (type solid)) (layer "F.SilkS"))
    (fp_line (start -2.202 2.0535) (end 2.248 2.0535)
      (stroke (width 0.15) (type solid)) (layer "F.SilkS"))
    (fp_line (start 2.248 -2.0555) (end 2.248 -1.5265)
      (stroke (width 0.15) (type solid)) (layer "F.SilkS"))
    (fp_line (start 2.248 2.0535) (end 2.248 1.5245)
      (stroke (width 0.15) (type solid)) (layer "F.SilkS"))
    (fp_rect (start -2.775 -2.35) (end 2.775 2.35)
      (stroke (width 0.05) (type solid)) (fill none) (layer "F.CrtYd"))
    (fp_line (start -2.202 -2.0555) (end 2.248 -2.0555)
      (stroke (width 0.15) (type solid)) (layer "F.Fab"))
    (fp_line (start -2.202 2.0295) (end -2.202 -2.0305)
      (stroke (width 0.15) (type solid)) (layer "F.Fab"))
    (fp_line (start 2.248 -2.0305) (end 2.248 2.0295)
      (stroke (width 0.15) (type solid)) (layer "F.Fab"))
    (fp_line (start 2.248 2.0535) (end -2.202 2.0535)
      (stroke (width 0.15) (type solid)) (layer "F.Fab"))
    (pad "1" smd roundrect (at -2 -0.0015 270) (size 1.4 1.9) (layers "F.Cu" "F.Paste" "F.Mask") (roundrect_rratio 0.05)
      (net 8 "Net-(U5-SW)") (pintype "passive"))
    (pad "2" smd roundrect (at 2 -0.0015 270) (size 1.4 1.9) (layers "F.Cu" "F.Paste" "F.Mask") (roundrect_rratio 0.05)
      (net 176 "VCC1V2") (pintype "passive"))
  )
	(footprint "data-center-rdimm-ddr4-tester-footprints:R_0402_1005Metric" (layer "F.Cu")
    (at 155.149328 114.102008 90)
    (descr "Resistor SMD 0402")
    (tags "resistor SMD 0402")
    (property "Author" "Antmicro")
    (property "License" "Apache-2.0")
    (property "MPN" "CR0402-FX-1002GLF")
    (property "Manufacturer" "Bourns")
    (property "Sheetfile" "supply.kicad_sch")
    (property "Sheetname" "Supply")
    (property "Tolerance" "1%")
    (property "Val" "10k")
    (property "ki_description" "10k resistor in 0402 package with 1% tolerance")
    (attr smd)
    (fp_text reference "R46" (at -1.067992 2.200672 90) (layer "F.SilkS")
        (effects (font (size 0.7 0.7) (thickness 0.15)) (justify left bottom))
    )
    (fp_text value "R_10k_0402" (at 0 1.4 90) (layer "F.Fab") hide
        (effects (font (size 0.7 0.7) (thickness 0.15)) (justify left bottom))
    )
    (fp_text user "License: Apache-2.0" (at -0.95 5.169 90) (layer "F.Fab") hide
        (effects (font (size 0.7 0.7) (thickness 0.15)) (justify left bottom))
    )
    (fp_text user "${REFERENCE}" (at -0.95 3.168 90) (layer "F.Fab") hide
        (effects (font (size 0.7 0.7) (thickness 0.15)) (justify left bottom))
    )
    (fp_text user "Author: Antmicro" (at -0.95 4.169 90) (layer "F.Fab") hide
        (effects (font (size 0.7 0.7) (thickness 0.15)) (justify left bottom))
    )
    (fp_rect (start -0.93 -0.47) (end 0.93 0.47)
      (stroke (width 0.05) (type solid)) (fill none) (layer "F.CrtYd"))
    (fp_rect (start -0.5 -0.25) (end 0.5 0.25)
      (stroke (width 0.15) (type solid)) (fill none) (layer "F.Fab"))
    (pad "1" smd roundrect (at -0.485 0 90) (size 0.59 0.64) (layers "F.Cu" "F.Paste" "F.Mask") (roundrect_rratio 0.25)
      (net 625 "Net-(U5-FB)") (pintype "passive"))
    (pad "2" smd roundrect (at 0.485 0 90) (size 0.59 0.64) (layers "F.Cu" "F.Paste" "F.Mask") (roundrect_rratio 0.25)
      (net 9 "GND") (pintype "passive"))
  )
)
